# T6G (Grand Teton) — schematic netlist excerpt (pin names and nets, part order shuffled) for the footprints in the layout excerpt that follows; sources: Cadence DE-HDL packaged netlist, KiCad conversion of 04192023_DAF0TMB3IC0_F0TG_MB_C_brd_V02_OCP.brd

PU31  ISL99390FRZTR5935  ISL99390FRZ-TR5935 IC  pkg QFN21_6X5XB  page 215
  VOS  = PVDDCR_SOC_P1_VOS2
  AGND  = GND
  VCC  = PVDDCR_SOC_P1_VCC2
  PVCC  = PVDDCR_CPU0_P1_PVCC
  PGND1  = GND
  GL1  = NC_PVDDCR_SOC_P1_GL1_2
  PGND2  = GND
  SW  = SW_PVDDCR_SOC_P1_SW2
  VIN1  = SW_P12V_AUX_PVDDCR_SOC_P1_FLT
  VIN2  = SW_P12V_AUX_PVDDCR_SOC_P1_FLT
  DNC  = NC_PVDDCR_SOC_P1_DNC2
  PHASE  = SW_PVDDCR_SOC_P1_PH2
  BOOT  = SW_PVDDCR_SOC_P1_BOOT2
  PWM  = PVDDCR_SOC_P1_PWM2
  EN  = PVDDCR_SOC_P1_VCC2
  TOUT_FLT  = PVDDCR_SOC_P1_TEMP1
  LSET  = PVDDCR_SOC_P1_LSET2
  IOUT  = PVDDCR_SOC_P1_IMON2
  REFIN  = PVDDCR_CPU0_P1_VCCS
  PGND3  = GND
  GL2  = NC_PVDDCR_SOC_P1_GL2_2

(kicad_pcb
	(version 20260206)
	(generator "pcbnew")
	(generator_version "10.0")
	(general
		(thickness 1.6)
		(legacy_teardrops no)
	)
	(paper "A4")
	(title_block
		(title "04192023_DAF0TMB3IC0_F0TG_MB_C_brd_V02_OCP.brd")
		(comment 1 "Grand Teton / footprints 180-180 of 8354")
	)
	(layers
		(0 "F.Cu" signal "TOP")
		(4 "In1.Cu" signal "GND")
		(6 "In2.Cu" signal "IN1")
		(8 "In3.Cu" signal "GND1")
		(10 "In4.Cu" signal "IN2")
		(12 "In5.Cu" signal "GND2")
		(14 "In6.Cu" signal "IN3")
		(16 "In7.Cu" signal "GND3")
		(18 "In8.Cu" signal "VCC")
		(20 "In9.Cu" signal "VCC1")
		(22 "In10.Cu" signal "GND4")
		(24 "In11.Cu" signal "IN4")
		(26 "In12.Cu" signal "GND5")
		(28 "In13.Cu" signal "IN5")
		(30 "In14.Cu" signal "GND6")
		(32 "In15.Cu" signal "IN6")
		(34 "In16.Cu" signal "GND7")
		(2 "B.Cu" signal "BOTTOM")
		(9 "F.Adhes" user "F.Adhesive")
		(11 "B.Adhes" user "B.Adhesive")
		(13 "F.Paste" user "Package Geometry/Pastemask Top")
		(15 "B.Paste" user "Package Geometry/Pastemask Bottom")
		(5 "F.SilkS" user "Ref Des/Silkscreen Top")
		(7 "B.SilkS" user "Ref Des/Silkscreen Bottom")
		(1 "F.Mask" user "Board Geometry/Soldermask Top")
		(3 "B.Mask" user "Board Geometry/Soldermask Bottom")
		(17 "Dwgs.User" user "User.Drawings")
		(19 "Cmts.User" user "User.Comments")
		(21 "Eco1.User" user "User.Eco1")
		(23 "Eco2.User" user "User.Eco2")
		(25 "Edge.Cuts" user "Board Geometry/Outline")
		(27 "Margin" user)
		(31 "F.CrtYd" user "Package Geometry/Place Bound Top")
		(29 "B.CrtYd" user "Package Geometry/Place Bound Bottom")
		(35 "F.Fab" user "Ref Des/Assembly Top")
		(33 "B.Fab" user "Ref Des/Assembly Bottom")
	)
	(footprint ""
		(layer "F.Cu")
		(at 123.96597 -165.192456 180)
		(property "Reference" "PU31"
			(at 2.577592 -7.079742 0)
			(unlocked yes)
			(layer "F.SilkS")
			(effects
				(font
					(size 0.7874 0.5842)
					(thickness 0.1524)
				)
				(justify left)
			)
		)
		(property "Value" ""
			(at 0 0 180)
			(layer "F.Fab")
			(effects
				(font
					(size 1.27 1.27)
				)
			)
		)
		(duplicate_pad_numbers_are_jumpers no)
		(fp_line
			(start 2.500122 2.999994)
			(end 2.2987 2.999994)
			(stroke
				(width 0.1524)
				(type default)
			)
			(layer "F.SilkS")
		)
		(fp_line
			(start 2.500122 2.339594)
			(end 2.500122 2.999994)
			(stroke
				(width 0.1524)
				(type default)
			)
			(layer "F.SilkS")
		)
		(fp_line
			(start 2.500122 -2.999994)
			(end 2.500122 -2.44348)
			(stroke
				(width 0.1524)
				(type default)
			)
			(layer "F.SilkS")
		)
		(fp_line
			(start 2.31394 -2.999994)
			(end 2.500122 -2.999994)
			(stroke
				(width 0.1524)
				(type default)
			)
			(layer "F.SilkS")
		)
		(fp_line
			(start -2.2987 2.999994)
			(end -2.500122 2.999994)
			(stroke
				(width 0.1524)
				(type default)
			)
			(layer "F.SilkS")
		)
		(fp_line
			(start -2.500122 2.999994)
			(end -2.500122 2.339594)
			(stroke
				(width 0.1524)
				(type default)
			)
			(layer "F.SilkS")
		)
		(fp_line
			(start -2.500122 0.6604)
			(end -2.500122 0.229108)
			(stroke
				(width 0.1524)
				(type default)
			)
			(layer "F.SilkS")
		)
		(fp_line
			(start -2.500122 -2.529078)
			(end -2.500122 -2.999994)
			(stroke
				(width 0.1524)
				(type default)
			)
			(layer "F.SilkS")
		)
		(fp_line
			(start -2.500122 -2.999994)
			(end -2.24409 -2.999994)
			(stroke
				(width 0.1524)
				(type default)
			)
			(layer "F.SilkS")
		)
		(fp_poly
			(pts
				(xy -2.757424 -2.445004) (xy -3.431032 -2.66954) (xy -2.98196 -3.118612)
			)
			(stroke
				(width 0)
				(type default)
			)
			(fill yes)
			(layer "F.SilkS")
		)
		(fp_line
			(start 2.500122 2.999994)
			(end -2.500122 2.999994)
			(stroke
				(width 0.1)
				(type default)
			)
			(layer "F.Fab")
		)
		(fp_line
			(start 2.500122 -2.999994)
			(end 2.500122 2.999994)
			(stroke
				(width 0.1)
				(type default)
			)
			(layer "F.Fab")
		)
		(fp_line
			(start -2.500122 2.999994)
			(end -2.500122 -2.999994)
			(stroke
				(width 0.1)
				(type default)
			)
			(layer "F.Fab")
		)
		(fp_line
			(start -2.500122 -2.999994)
			(end 2.500122 -2.999994)
			(stroke
				(width 0.1)
				(type default)
			)
			(layer "F.Fab")
		)
		(fp_poly
			(pts
				(xy -4.218432 -2.783078) (xy -4.218432 -1.767078) (xy -3.202432 -2.275078)
			)
			(stroke
				(width 0)
				(type default)
			)
			(fill yes)
			(layer "F.Fab")
		)
		(pad "1" smd rect
			(at -2.400046 -2.275078 270)
			(size 0.2286 0.6096)
			(layers "F.Cu" "F.Mask" "F.Paste")
			(net "PVDDCR_SOC_P1_VOS2")
		)
		(pad "2" smd rect
			(at -2.400046 -1.82499 270)
			(size 0.2286 0.6096)
			(layers "F.Cu" "F.Mask" "F.Paste")
			(net "GND")
		)
		(pad "3" smd rect
			(at -2.400046 -1.374902 270)
			(size 0.2286 0.6096)
			(layers "F.Cu" "F.Mask" "F.Paste")
			(net "PVDDCR_SOC_P1_VCC2")
		)
		(pad "4" smd rect
			(at -2.400046 -0.925068 270)
			(size 0.2286 0.6096)
			(layers "F.Cu" "F.Mask" "F.Paste")
			(net "PVDDCR_CPU0_P1_PVCC")
		)
		(pad "5" smd rect
			(at -2.400046 -0.47498 270)
			(size 0.2286 0.6096)
			(layers "F.Cu" "F.Mask" "F.Paste")
			(net "GND")
		)
		(pad "6" smd rect
			(at -2.400046 -0.024892 270)
			(size 0.2286 0.6096)
			(layers "F.Cu" "F.Mask" "F.Paste")
			(net "NC_PVDDCR_SOC_P1_GL1_2")
		)
		(pad "7_9-20_24" smd circle
			(at 0 1.150112 270)
			(size 0 0)
			(layers "F.Cu" "F.Mask" "F.Paste")
			(net "GND")
		)
		(pad "10_19" smd rect
			(at 0 2.899918 270)
			(size 0.6096 4.318)
			(layers "F.Cu" "F.Mask" "F.Paste")
			(net "SW_PVDDCR_SOC_P1_SW2")
		)
		(pad "25_29" smd rect
			(at 1.549908 -1.279906 90)
			(size 2.0574 2.3114)
			(layers "F.Cu" "F.Mask" "F.Paste")
			(net "SW_P12V_AUX_PVDDCR_SOC_P1_FLT")
		)
		(pad "30" smd rect
			(at 2.05994 -2.899918 180)
			(size 0.2286 0.6096)
			(layers "F.Cu" "F.Mask" "F.Paste")
			(net "SW_P12V_AUX_PVDDCR_SOC_P1_FLT")
		)
		(pad "31" smd rect
			(at 1.610106 -2.899918 180)
			(size 0.2286 0.6096)
			(layers "F.Cu" "F.Mask" "F.Paste")
			(net "NC_PVDDCR_SOC_P1_DNC2")
		)
		(pad "32" smd rect
			(at 1.160018 -2.899918 180)
			(size 0.2286 0.6096)
			(layers "F.Cu" "F.Mask" "F.Paste")
			(net "SW_PVDDCR_SOC_P1_PH2")
		)
		(pad "33" smd rect
			(at 0.70993 -2.899918 180)
			(size 0.2286 0.6096)
			(layers "F.Cu" "F.Mask" "F.Paste")
			(net "SW_PVDDCR_SOC_P1_BOOT2")
		)
		(pad "34" smd rect
			(at 0.260096 -2.899918 180)
			(size 0.2286 0.6096)
			(layers "F.Cu" "F.Mask" "F.Paste")
			(net "PVDDCR_SOC_P1_PWM2")
		)
		(pad "35" smd rect
			(at -0.189992 -2.899918 180)
			(size 0.2286 0.6096)
			(layers "F.Cu" "F.Mask" "F.Paste")
			(net "PVDDCR_SOC_P1_VCC2")
		)
		(pad "36" smd rect
			(at -0.64008 -2.899918 180)
			(size 0.2286 0.6096)
			(layers "F.Cu" "F.Mask" "F.Paste")
			(net "PVDDCR_SOC_P1_TEMP1")
		)
		(pad "37" smd rect
			(at -1.089914 -2.899918 180)
			(size 0.2286 0.6096)
			(layers "F.Cu" "F.Mask" "F.Paste")
			(net "PVDDCR_SOC_P1_LSET2")
		)
		(pad "38" smd rect
			(at -1.540002 -2.899918 180)
			(size 0.2286 0.6096)
			(layers "F.Cu" "F.Mask" "F.Paste")
			(net "PVDDCR_SOC_P1_IMON2")
		)
		(pad "39" smd rect
			(at -1.99009 -2.899918 180)
			(size 0.2286 0.6096)
			(layers "F.Cu" "F.Mask" "F.Paste")
			(net "PVDDCR_CPU0_P1_VCCS")
		)
		(pad "40" smd rect
			(at -0.87503 -1.27508 180)
			(size 1.7526 1.9558)
			(layers "F.Cu" "F.Mask" "F.Paste")
			(net "GND")
		)
		(pad "41" smd rect
			(at -1.525016 0.249936 90)
			(size 0.3048 0.4572)
			(layers "F.Cu" "F.Mask" "F.Paste")
			(net "NC_PVDDCR_SOC_P1_GL2_2")
		)
		(zone
			(layer "F.Cu")
			(hatch none 0.5)
			(connect_pads
				(clearance 0)
			)
			(min_thickness 0.25)
			(keepout
				(tracks not_allowed)
				(vias allowed)
				(pads allowed)
				(copperpour not_allowed)
				(footprints allowed)
			)
			(placement
				(enabled no)
				(sheetname "")
			)
			(fill
				(thermal_gap 0.5)
				(thermal_bridge_width 0.5)
				(island_removal_mode 0)
			)
			(polygon
				(pts
					(xy 126.466092 -167.736774) (xy 126.466092 -167.44315) (xy 121.465848 -167.44315) (xy 121.465848 -167.736774)
					(xy 121.75617 -167.736774) (xy 126.17577 -167.736774)
				)
			)
		)
		(zone
			(layer "F.Cu")
			(hatch none 0.5)
			(connect_pads
				(clearance 0)
			)
			(min_thickness 0.25)
			(keepout
				(tracks not_allowed)
				(vias allowed)
				(pads allowed)
				(copperpour not_allowed)
				(footprints allowed)
			)
			(placement
				(enabled no)
				(sheetname "")
			)
			(fill
				(thermal_gap 0.5)
				(thermal_bridge_width 0.5)
				(island_removal_mode 0)
			)
			(polygon
				(pts
					(xy 123.9139 -164.946076) (xy 123.9139 -162.888676) (xy 125.7681 -162.888676) (xy 125.7681 -163.129722)
					(xy 126.010416 -163.129722) (xy 126.010416 -162.648138) (xy 122.131582 -162.648138) (xy 122.131582 -162.83305)
					(xy 123.622562 -162.83305) (xy 123.622562 -164.99205) (xy 121.465848 -164.99205) (xy 121.465848 -165.241732)
					(xy 123.618244 -165.241732)
				)
			)
		)
	)
)
